# T6G (Grand Teton) — schematic netlist excerpt (pin names and nets, part order shuffled) for the footprints in the layout excerpt that follows; sources: Cadence DE-HDL packaged netlist, KiCad conversion of 04192023_DAF0TMB3IC0_F0TG_MB_C_brd_V02_OCP.brd

R6122  Q_RES  1K 1% EMPTY  pkg 0402LF  page 84 : A = PVDD18_S5_P0 ; B = FM_BOARD_SKU_ID2
R556  Q_RES  1K 1% EMPTY  pkg 0402LF  page 55 : A = PVDD18_S5_P1 ; B = RST_CPU1_RESETL_N

(kicad_pcb
	(version 20260206)
	(generator "pcbnew")
	(generator_version "10.0")
	(general
		(thickness 1.6)
		(legacy_teardrops no)
	)
	(paper "A4")
	(title_block
		(title "04192023_DAF0TMB3IC0_F0TG_MB_C_brd_V02_OCP.brd")
		(comment 1 "Grand Teton / footprints 5784-5785 of 8354")
	)
	(layers
		(0 "F.Cu" signal "TOP")
		(4 "In1.Cu" signal "GND")
		(6 "In2.Cu" signal "IN1")
		(8 "In3.Cu" signal "GND1")
		(10 "In4.Cu" signal "IN2")
		(12 "In5.Cu" signal "GND2")
		(14 "In6.Cu" signal "IN3")
		(16 "In7.Cu" signal "GND3")
		(18 "In8.Cu" signal "VCC")
		(20 "In9.Cu" signal "VCC1")
		(22 "In10.Cu" signal "GND4")
		(24 "In11.Cu" signal "IN4")
		(26 "In12.Cu" signal "GND5")
		(28 "In13.Cu" signal "IN5")
		(30 "In14.Cu" signal "GND6")
		(32 "In15.Cu" signal "IN6")
		(34 "In16.Cu" signal "GND7")
		(2 "B.Cu" signal "BOTTOM")
		(9 "F.Adhes" user "F.Adhesive")
		(11 "B.Adhes" user "B.Adhesive")
		(13 "F.Paste" user "Package Geometry/Pastemask Top")
		(15 "B.Paste" user "Package Geometry/Pastemask Bottom")
		(5 "F.SilkS" user "Ref Des/Silkscreen Top")
		(7 "B.SilkS" user "Ref Des/Silkscreen Bottom")
		(1 "F.Mask" user "Board Geometry/Soldermask Top")
		(3 "B.Mask" user "Board Geometry/Soldermask Bottom")
		(17 "Dwgs.User" user "User.Drawings")
		(19 "Cmts.User" user "User.Comments")
		(21 "Eco1.User" user "User.Eco1")
		(23 "Eco2.User" user "User.Eco2")
		(25 "Edge.Cuts" user "Board Geometry/Outline")
		(27 "Margin" user)
		(31 "F.CrtYd" user "Package Geometry/Place Bound Top")
		(29 "B.CrtYd" user "Package Geometry/Place Bound Bottom")
		(35 "F.Fab" user "Ref Des/Assembly Top")
		(33 "B.Fab" user "Ref Des/Assembly Bottom")
	)
	(footprint ""
		(layer "B.Cu")
		(at 405.241252 -349.195644 -90)
		(property "Reference" "R6122"
			(at 0 0 90)
			(layer "B.SilkS")
			(hide yes)
			(effects
				(font
					(size 1.27 1.27)
				)
				(justify mirror)
			)
		)
		(property "Value" ""
			(at 0 0 90)
			(layer "B.Fab")
			(effects
				(font
					(size 1.27 1.27)
				)
				(justify mirror)
			)
		)
		(duplicate_pad_numbers_are_jumpers no)
		(fp_line
			(start -0.7874 0.4064)
			(end 0.7874 0.4064)
			(stroke
				(width 0.1524)
				(type default)
			)
			(layer "B.SilkS")
		)
		(fp_line
			(start 0.7874 0.4064)
			(end 0.7874 -0.4064)
			(stroke
				(width 0.1524)
				(type default)
			)
			(layer "B.SilkS")
		)
		(fp_line
			(start -0.7874 -0.4064)
			(end -0.7874 0.4064)
			(stroke
				(width 0.1524)
				(type default)
			)
			(layer "B.SilkS")
		)
		(fp_line
			(start 0.7874 -0.4064)
			(end -0.7874 -0.4064)
			(stroke
				(width 0.1524)
				(type default)
			)
			(layer "B.SilkS")
		)
		(fp_line
			(start -0.67945 0.3048)
			(end -0.120396 0.3048)
			(stroke
				(width 0.1)
				(type default)
			)
			(layer "B.Fab")
		)
		(fp_line
			(start -0.120396 0.3048)
			(end -0.120396 0.2794)
			(stroke
				(width 0.1)
				(type default)
			)
			(layer "B.Fab")
		)
		(fp_line
			(start 0.12065 0.3048)
			(end 0.67945 0.3048)
			(stroke
				(width 0.1)
				(type default)
			)
			(layer "B.Fab")
		)
		(fp_line
			(start 0.67945 0.3048)
			(end 0.67945 -0.305054)
			(stroke
				(width 0.1)
				(type default)
			)
			(layer "B.Fab")
		)
		(fp_line
			(start -0.120396 0.2794)
			(end 0.12065 0.2794)
			(stroke
				(width 0.1)
				(type default)
			)
			(layer "B.Fab")
		)
		(fp_line
			(start 0.12065 0.2794)
			(end 0.12065 0.3048)
			(stroke
				(width 0.1)
				(type default)
			)
			(layer "B.Fab")
		)
		(fp_line
			(start -0.12065 -0.2794)
			(end -0.12065 -0.3048)
			(stroke
				(width 0.1)
				(type default)
			)
			(layer "B.Fab")
		)
		(fp_line
			(start 0.12065 -0.2794)
			(end -0.12065 -0.2794)
			(stroke
				(width 0.1)
				(type default)
			)
			(layer "B.Fab")
		)
		(fp_line
			(start -0.67945 -0.3048)
			(end -0.67945 0.3048)
			(stroke
				(width 0.1)
				(type default)
			)
			(layer "B.Fab")
		)
		(fp_line
			(start -0.12065 -0.3048)
			(end -0.67945 -0.3048)
			(stroke
				(width 0.1)
				(type default)
			)
			(layer "B.Fab")
		)
		(fp_line
			(start 0.12065 -0.305054)
			(end 0.12065 -0.2794)
			(stroke
				(width 0.1)
				(type default)
			)
			(layer "B.Fab")
		)
		(fp_line
			(start 0.67945 -0.305054)
			(end 0.12065 -0.305054)
			(stroke
				(width 0.1)
				(type default)
			)
			(layer "B.Fab")
		)
		(pad "1" smd circle
			(at 0.40005 0 90)
			(size 0 0)
			(layers "B.Cu" "B.Mask" "B.Paste")
			(net "PVDD18_S5_P0")
		)
		(pad "2" smd circle
			(at -0.40005 0 90)
			(size 0 0)
			(layers "B.Cu" "B.Mask" "B.Paste")
			(net "FM_BOARD_SKU_ID2")
		)
	)
	(footprint ""
		(layer "B.Cu")
		(at 68.547234 -201.545952 90)
		(property "Reference" "R556"
			(at 0 0 90)
			(layer "B.SilkS")
			(hide yes)
			(effects
				(font
					(size 1.27 1.27)
				)
				(justify mirror)
			)
		)
		(property "Value" ""
			(at 0 0 90)
			(layer "B.Fab")
			(effects
				(font
					(size 1.27 1.27)
				)
				(justify mirror)
			)
		)
		(duplicate_pad_numbers_are_jumpers no)
		(fp_line
			(start 0.7874 -0.4064)
			(end -0.7874 -0.4064)
			(stroke
				(width 0.1524)
				(type default)
			)
			(layer "B.SilkS")
		)
		(fp_line
			(start -0.7874 -0.4064)
			(end -0.7874 0.4064)
			(stroke
				(width 0.1524)
				(type default)
			)
			(layer "B.SilkS")
		)
		(fp_line
			(start 0.7874 0.4064)
			(end 0.7874 -0.4064)
			(stroke
				(width 0.1524)
				(type default)
			)
			(layer "B.SilkS")
		)
		(fp_line
			(start -0.7874 0.4064)
			(end 0.7874 0.4064)
			(stroke
				(width 0.1524)
				(type default)
			)
			(layer "B.SilkS")
		)
		(fp_line
			(start 0.67945 -0.305054)
			(end 0.12065 -0.305054)
			(stroke
				(width 0.1)
				(type default)
			)
			(layer "B.Fab")
		)
		(fp_line
			(start 0.12065 -0.305054)
			(end 0.12065 -0.2794)
			(stroke
				(width 0.1)
				(type default)
			)
			(layer "B.Fab")
		)
		(fp_line
			(start -0.12065 -0.3048)
			(end -0.67945 -0.3048)
			(stroke
				(width 0.1)
				(type default)
			)
			(layer "B.Fab")
		)
		(fp_line
			(start -0.67945 -0.3048)
			(end -0.67945 0.3048)
			(stroke
				(width 0.1)
				(type default)
			)
			(layer "B.Fab")
		)
		(fp_line
			(start 0.12065 -0.2794)
			(end -0.12065 -0.2794)
			(stroke
				(width 0.1)
				(type default)
			)
			(layer "B.Fab")
		)
		(fp_line
			(start -0.12065 -0.2794)
			(end -0.12065 -0.3048)
			(stroke
				(width 0.1)
				(type default)
			)
			(layer "B.Fab")
		)
		(fp_line
			(start 0.12065 0.2794)
			(end 0.12065 0.3048)
			(stroke
				(width 0.1)
				(type default)
			)
			(layer "B.Fab")
		)
		(fp_line
			(start -0.120396 0.2794)
			(end 0.12065 0.2794)
			(stroke
				(width 0.1)
				(type default)
			)
			(layer "B.Fab")
		)
		(fp_line
			(start 0.67945 0.3048)
			(end 0.67945 -0.305054)
			(stroke
				(width 0.1)
				(type default)
			)
			(layer "B.Fab")
		)
		(fp_line
			(start 0.12065 0.3048)
			(end 0.67945 0.3048)
			(stroke
				(width 0.1)
				(type default)
			)
			(layer "B.Fab")
		)
		(fp_line
			(start -0.120396 0.3048)
			(end -0.120396 0.2794)
			(stroke
				(width 0.1)
				(type default)
			)
			(layer "B.Fab")
		)
		(fp_line
			(start -0.67945 0.3048)
			(end -0.120396 0.3048)
			(stroke
				(width 0.1)
				(type default)
			)
			(layer "B.Fab")
		)
		(pad "1" smd circle
			(at 0.40005 0 270)
			(size 0 0)
			(layers "B.Cu" "B.Mask" "B.Paste")
			(net "PVDD18_S5_P1")
		)
		(pad "2" smd circle
			(at -0.40005 0 270)
			(size 0 0)
			(layers "B.Cu" "B.Mask" "B.Paste")
			(net "RST_CPU1_RESETL_N")
		)
	)
)
